(kicad_pcb
	(version 20260206)
	(generator "pcbnew")
	(generator_version "10.0")
	(general
		(thickness 1.6)
		(legacy_teardrops no)
	)
	(paper "A4")
	(title_block
		(title "04192023_DAF0TMB3IC0_F0TG_MB_C_brd_V02_OCP.brd")
		(comment 1 "Grand Teton / footprints 3963-3968 of 8354")
	)
	(layers
		(0 "F.Cu" signal "TOP")
		(4 "In1.Cu" signal "GND")
		(6 "In2.Cu" signal "IN1")
		(8 "In3.Cu" signal "GND1")
		(10 "In4.Cu" signal "IN2")
		(12 "In5.Cu" signal "GND2")
		(14 "In6.Cu" signal "IN3")
		(16 "In7.Cu" signal "GND3")
		(18 "In8.Cu" signal "VCC")
		(20 "In9.Cu" signal "VCC1")
		(22 "In10.Cu" signal "GND4")
		(24 "In11.Cu" signal "IN4")
		(26 "In12.Cu" signal "GND5")
		(28 "In13.Cu" signal "IN5")
		(30 "In14.Cu" signal "GND6")
		(32 "In15.Cu" signal "IN6")
		(34 "In16.Cu" signal "GND7")
		(2 "B.Cu" signal "BOTTOM")
		(9 "F.Adhes" user "F.Adhesive")
		(11 "B.Adhes" user "B.Adhesive")
		(13 "F.Paste" user "Package Geometry/Pastemask Top")
		(15 "B.Paste" user "Package Geometry/Pastemask Bottom")
		(5 "F.SilkS" user "Ref Des/Silkscreen Top")
		(7 "B.SilkS" user "Ref Des/Silkscreen Bottom")
		(1 "F.Mask" user "Board Geometry/Soldermask Top")
		(3 "B.Mask" user "Board Geometry/Soldermask Bottom")
		(17 "Dwgs.User" user "User.Drawings")
		(19 "Cmts.User" user "User.Comments")
		(21 "Eco1.User" user "User.Eco1")
		(23 "Eco2.User" user "User.Eco2")
		(25 "Edge.Cuts" user "Board Geometry/Outline")
		(27 "Margin" user)
		(31 "F.CrtYd" user "Package Geometry/Place Bound Top")
		(29 "B.CrtYd" user "Package Geometry/Place Bound Bottom")
		(35 "F.Fab" user "Ref Des/Assembly Top")
		(33 "B.Fab" user "Ref Des/Assembly Bottom")
	)
	(footprint ""
		(layer "F.Cu")
		(at 325.740776 -384.449828)
		(property "Reference" "C905"
			(at 0 0 0)
			(layer "F.SilkS")
			(hide yes)
			(effects
				(font
					(size 1.27 1.27)
				)
			)
		)
		(property "Value" ""
			(at 0 0 0)
			(layer "F.Fab")
			(effects
				(font
					(size 1.27 1.27)
				)
			)
		)
		(duplicate_pad_numbers_are_jumpers no)
		(fp_line
			(start -0.299974 -0.150114)
			(end 0.299974 -0.150114)
			(stroke
				(width 0.1)
				(type default)
			)
			(layer "F.Fab")
		)
		(fp_line
			(start -0.299974 0.150114)
			(end -0.299974 -0.150114)
			(stroke
				(width 0.1)
				(type default)
			)
			(layer "F.Fab")
		)
		(fp_line
			(start 0.299974 -0.150114)
			(end 0.299974 0.150114)
			(stroke
				(width 0.1)
				(type default)
			)
			(layer "F.Fab")
		)
		(fp_line
			(start 0.299974 0.150114)
			(end -0.299974 0.150114)
			(stroke
				(width 0.1)
				(type default)
			)
			(layer "F.Fab")
		)
		(pad "1" smd rect
			(at -0.2667 0)
			(size 0.3048 0.381)
			(layers "F.Cu" "F.Mask" "F.Paste")
			(net "P5E_CPU0_P0_TX_C_DP<14>")
		)
		(pad "2" smd rect
			(at 0.2667 0)
			(size 0.3048 0.381)
			(layers "F.Cu" "F.Mask" "F.Paste")
			(net "P5E_CPU0_P0_TX_DP<14>")
		)
	)
	(footprint ""
		(layer "F.Cu")
		(at 191.41694 -401.325842 180)
		(property "Reference" "PR3928"
			(at 0 0 180)
			(layer "F.SilkS")
			(hide yes)
			(effects
				(font
					(size 1.27 1.27)
				)
			)
		)
		(property "Value" ""
			(at 0 0 180)
			(layer "F.Fab")
			(effects
				(font
					(size 1.27 1.27)
				)
			)
		)
		(duplicate_pad_numbers_are_jumpers no)
		(fp_line
			(start 0.7874 0.4064)
			(end -0.7874 0.4064)
			(stroke
				(width 0.1524)
				(type default)
			)
			(layer "F.SilkS")
		)
		(fp_line
			(start 0.7874 -0.4064)
			(end 0.7874 0.4064)
			(stroke
				(width 0.1524)
				(type default)
			)
			(layer "F.SilkS")
		)
		(fp_line
			(start -0.7874 0.4064)
			(end -0.7874 -0.4064)
			(stroke
				(width 0.1524)
				(type default)
			)
			(layer "F.SilkS")
		)
		(fp_line
			(start -0.7874 -0.4064)
			(end 0.7874 -0.4064)
			(stroke
				(width 0.1524)
				(type default)
			)
			(layer "F.SilkS")
		)
		(fp_line
			(start 0.67945 0.3048)
			(end 0.120396 0.3048)
			(stroke
				(width 0.1)
				(type default)
			)
			(layer "F.Fab")
		)
		(fp_line
			(start 0.67945 -0.3048)
			(end 0.67945 0.3048)
			(stroke
				(width 0.1)
				(type default)
			)
			(layer "F.Fab")
		)
		(fp_line
			(start 0.12065 -0.2794)
			(end 0.12065 -0.3048)
			(stroke
				(width 0.1)
				(type default)
			)
			(layer "F.Fab")
		)
		(fp_line
			(start 0.12065 -0.3048)
			(end 0.67945 -0.3048)
			(stroke
				(width 0.1)
				(type default)
			)
			(layer "F.Fab")
		)
		(fp_line
			(start 0.120396 0.3048)
			(end 0.120396 0.2794)
			(stroke
				(width 0.1)
				(type default)
			)
			(layer "F.Fab")
		)
		(fp_line
			(start 0.120396 0.2794)
			(end -0.12065 0.2794)
			(stroke
				(width 0.1)
				(type default)
			)
			(layer "F.Fab")
		)
		(fp_line
			(start -0.12065 0.3048)
			(end -0.67945 0.3048)
			(stroke
				(width 0.1)
				(type default)
			)
			(layer "F.Fab")
		)
		(fp_line
			(start -0.12065 0.2794)
			(end -0.12065 0.3048)
			(stroke
				(width 0.1)
				(type default)
			)
			(layer "F.Fab")
		)
		(fp_line
			(start -0.12065 -0.2794)
			(end 0.12065 -0.2794)
			(stroke
				(width 0.1)
				(type default)
			)
			(layer "F.Fab")
		)
		(fp_line
			(start -0.12065 -0.305054)
			(end -0.12065 -0.2794)
			(stroke
				(width 0.1)
				(type default)
			)
			(layer "F.Fab")
		)
		(fp_line
			(start -0.67945 0.3048)
			(end -0.67945 -0.305054)
			(stroke
				(width 0.1)
				(type default)
			)
			(layer "F.Fab")
		)
		(fp_line
			(start -0.67945 -0.305054)
			(end -0.12065 -0.305054)
			(stroke
				(width 0.1)
				(type default)
			)
			(layer "F.Fab")
		)
		(pad "1" smd circle
			(at -0.40005 0 180)
			(size 0 0)
			(layers "F.Cu" "F.Mask" "F.Paste")
			(net "HSC_ON")
		)
		(pad "2" smd circle
			(at 0.40005 0 180)
			(size 0 0)
			(layers "F.Cu" "F.Mask" "F.Paste")
			(net "HSC_ON_R")
		)
	)
	(footprint ""
		(layer "F.Cu")
		(at 330.057506 -23.574248 180)
		(property "Reference" "JP12"
			(at 2.044446 -1.387094 90)
			(unlocked yes)
			(layer "F.SilkS")
			(effects
				(font
					(size 0.7874 0.5842)
					(thickness 0.1524)
				)
				(justify left)
			)
		)
		(property "Value" ""
			(at 0 0 180)
			(layer "F.Fab")
			(effects
				(font
					(size 1.27 1.27)
				)
			)
		)
		(duplicate_pad_numbers_are_jumpers no)
		(fp_line
			(start 1.249934 6.400038)
			(end -1.249934 6.400038)
			(stroke
				(width 0.1524)
				(type default)
			)
			(layer "F.SilkS")
		)
		(fp_line
			(start 1.249934 -1.320038)
			(end 1.249934 6.400038)
			(stroke
				(width 0.1524)
				(type default)
			)
			(layer "F.SilkS")
		)
		(fp_line
			(start -1.249934 6.400038)
			(end -1.249934 -1.320038)
			(stroke
				(width 0.1524)
				(type default)
			)
			(layer "F.SilkS")
		)
		(fp_line
			(start -1.249934 -1.320038)
			(end 1.249934 -1.320038)
			(stroke
				(width 0.1524)
				(type default)
			)
			(layer "F.SilkS")
		)
		(fp_poly
			(pts
				(xy -2.382266 0.655828) (xy -1.465072 0.410972) (xy -1.819402 1.291844)
			)
			(stroke
				(width 0)
				(type default)
			)
			(fill yes)
			(layer "F.SilkS")
		)
		(fp_line
			(start 1.249934 6.400038)
			(end -1.249934 6.400038)
			(stroke
				(width 0.1)
				(type default)
			)
			(layer "F.Fab")
		)
		(fp_line
			(start 1.249934 -1.320038)
			(end 1.249934 6.400038)
			(stroke
				(width 0.1)
				(type default)
			)
			(layer "F.Fab")
		)
		(fp_line
			(start -1.249934 6.400038)
			(end -1.249934 -1.320038)
			(stroke
				(width 0.1)
				(type default)
			)
			(layer "F.Fab")
		)
		(fp_line
			(start -1.249934 -1.320038)
			(end 1.249934 -1.320038)
			(stroke
				(width 0.1)
				(type default)
			)
			(layer "F.Fab")
		)
		(fp_poly
			(pts
				(xy -2.5654 -0.556514) (xy -1.452372 0) (xy -2.5654 0.556514)
			)
			(stroke
				(width 0)
				(type default)
			)
			(fill yes)
			(layer "F.Fab")
		)
		(fp_text user "3"
			(at -1.778 5.13207 180)
			(unlocked yes)
			(layer "F.SilkS")
			(effects
				(font
					(size 0.7874 0.5842)
					(thickness 0.1524)
				)
			)
		)
		(fp_text user "1"
			(at -1.143 0.02667 180)
			(unlocked yes)
			(layer "B.SilkS")
			(effects
				(font
					(size 0.7874 0.5842)
					(thickness 0.1524)
				)
				(justify mirror)
			)
		)
		(fp_text user "3"
			(at -1.1557 5.18287 180)
			(unlocked yes)
			(layer "B.SilkS")
			(effects
				(font
					(size 0.7874 0.5842)
					(thickness 0.1524)
				)
				(justify mirror)
			)
		)
		(fp_text user "1"
			(at -1.143 0.02667 180)
			(unlocked yes)
			(layer "B.Fab")
			(effects
				(font
					(size 0.7874 0.5842)
					(thickness 0.1524)
				)
				(justify mirror)
			)
		)
		(fp_text user "3"
			(at -1.1557 5.18287 180)
			(unlocked yes)
			(layer "B.Fab")
			(effects
				(font
					(size 0.7874 0.5842)
					(thickness 0.1524)
				)
				(justify mirror)
			)
		)
		(fp_text user "3"
			(at -1.778 5.13207 180)
			(unlocked yes)
			(layer "F.Fab")
			(effects
				(font
					(size 0.7874 0.5842)
					(thickness 0.1524)
				)
			)
		)
		(pad "1" thru_hole rect
			(at 0 0 180)
			(size 1.5494 1.5494)
			(drill 1.0414)
			(layers "*.Cu" "*.Mask")
			(remove_unused_layers no)
			(net "P1V5_BAT_OUT_R")
			(clearance 0)
			(padstack
				(mode front_inner_back)
				(layer "Inner"
					(shape circle)
					(size 1.5494 1.5494)
					(clearance 0)
				)
				(layer "B.Cu"
					(shape rect)
					(size 1.5494 1.5494)
					(clearance 0)
				)
			)
		)
		(pad "2" thru_hole circle
			(at 0 2.54 180)
			(size 1.5494 1.5494)
			(drill 1.0414)
			(layers "*.Cu" "*.Mask")
			(remove_unused_layers no)
			(net "P1V5_BAT")
			(clearance 0)
		)
		(pad "3" thru_hole circle
			(at 0 5.08 180)
			(size 1.5494 1.5494)
			(drill 1.0414)
			(layers "*.Cu" "*.Mask")
			(remove_unused_layers no)
			(net "GND")
			(clearance 0)
		)
	)
	(footprint ""
		(layer "F.Cu")
		(at 452.153274 -50.266346 180)
		(property "Reference" "PC568"
			(at 0 0 180)
			(layer "F.SilkS")
			(hide yes)
			(effects
				(font
					(size 1.27 1.27)
				)
			)
		)
		(property "Value" ""
			(at 0 0 180)
			(layer "F.Fab")
			(effects
				(font
					(size 1.27 1.27)
				)
			)
		)
		(duplicate_pad_numbers_are_jumpers no)
		(fp_line
			(start 0.7874 0.4064)
			(end -0.7874 0.4064)
			(stroke
				(width 0.1524)
				(type default)
			)
			(layer "F.SilkS")
		)
		(fp_line
			(start 0.7874 -0.4064)
			(end 0.7874 0.4064)
			(stroke
				(width 0.1524)
				(type default)
			)
			(layer "F.SilkS")
		)
		(fp_line
			(start -0.7874 0.4064)
			(end -0.7874 -0.4064)
			(stroke
				(width 0.1524)
				(type default)
			)
			(layer "F.SilkS")
		)
		(fp_line
			(start -0.7874 -0.4064)
			(end 0.7874 -0.4064)
			(stroke
				(width 0.1524)
				(type default)
			)
			(layer "F.SilkS")
		)
		(fp_line
			(start 0.67945 0.3048)
			(end 0.120396 0.3048)
			(stroke
				(width 0.1)
				(type default)
			)
			(layer "F.Fab")
		)
		(fp_line
			(start 0.67945 -0.3048)
			(end 0.67945 0.3048)
			(stroke
				(width 0.1)
				(type default)
			)
			(layer "F.Fab")
		)
		(fp_line
			(start 0.12065 -0.2794)
			(end 0.12065 -0.3048)
			(stroke
				(width 0.1)
				(type default)
			)
			(layer "F.Fab")
		)
		(fp_line
			(start 0.12065 -0.3048)
			(end 0.67945 -0.3048)
			(stroke
				(width 0.1)
				(type default)
			)
			(layer "F.Fab")
		)
		(fp_line
			(start 0.120396 0.3048)
			(end 0.120396 0.2794)
			(stroke
				(width 0.1)
				(type default)
			)
			(layer "F.Fab")
		)
		(fp_line
			(start 0.120396 0.2794)
			(end -0.12065 0.2794)
			(stroke
				(width 0.1)
				(type default)
			)
			(layer "F.Fab")
		)
		(fp_line
			(start -0.12065 0.3048)
			(end -0.67945 0.3048)
			(stroke
				(width 0.1)
				(type default)
			)
			(layer "F.Fab")
		)
		(fp_line
			(start -0.12065 0.2794)
			(end -0.12065 0.3048)
			(stroke
				(width 0.1)
				(type default)
			)
			(layer "F.Fab")
		)
		(fp_line
			(start -0.12065 -0.2794)
			(end 0.12065 -0.2794)
			(stroke
				(width 0.1)
				(type default)
			)
			(layer "F.Fab")
		)
		(fp_line
			(start -0.12065 -0.305054)
			(end -0.12065 -0.2794)
			(stroke
				(width 0.1)
				(type default)
			)
			(layer "F.Fab")
		)
		(fp_line
			(start -0.67945 0.3048)
			(end -0.67945 -0.305054)
			(stroke
				(width 0.1)
				(type default)
			)
			(layer "F.Fab")
		)
		(fp_line
			(start -0.67945 -0.305054)
			(end -0.12065 -0.305054)
			(stroke
				(width 0.1)
				(type default)
			)
			(layer "F.Fab")
		)
		(pad "1" smd circle
			(at -0.40005 0 180)
			(size 0 0)
			(layers "F.Cu" "F.Mask" "F.Paste")
			(net "SW_P3V3_AUX_BOOTR")
		)
		(pad "2" smd circle
			(at 0.40005 0 180)
			(size 0 0)
			(layers "F.Cu" "F.Mask" "F.Paste")
			(net "SW_P3V3_AUX_BOOT_R")
		)
	)
	(footprint ""
		(layer "F.Cu")
		(at 151.257 -125.349)
		(property "Reference" "R8087"
			(at 0 0 0)
			(layer "F.SilkS")
			(hide yes)
			(effects
				(font
					(size 1.27 1.27)
				)
			)
		)
		(property "Value" ""
			(at 0 0 0)
			(layer "F.Fab")
			(effects
				(font
					(size 1.27 1.27)
				)
			)
		)
		(duplicate_pad_numbers_are_jumpers no)
		(fp_line
			(start -0.7874 -0.4064)
			(end 0.7874 -0.4064)
			(stroke
				(width 0.1524)
				(type default)
			)
			(layer "F.SilkS")
		)
		(fp_line
			(start -0.7874 0.4064)
			(end -0.7874 -0.4064)
			(stroke
				(width 0.1524)
				(type default)
			)
			(layer "F.SilkS")
		)
		(fp_line
			(start 0.7874 -0.4064)
			(end 0.7874 0.4064)
			(stroke
				(width 0.1524)
				(type default)
			)
			(layer "F.SilkS")
		)
		(fp_line
			(start 0.7874 0.4064)
			(end -0.7874 0.4064)
			(stroke
				(width 0.1524)
				(type default)
			)
			(layer "F.SilkS")
		)
		(fp_line
			(start -0.67945 -0.305054)
			(end -0.12065 -0.305054)
			(stroke
				(width 0.1)
				(type default)
			)
			(layer "F.Fab")
		)
		(fp_line
			(start -0.67945 0.3048)
			(end -0.67945 -0.305054)
			(stroke
				(width 0.1)
				(type default)
			)
			(layer "F.Fab")
		)
		(fp_line
			(start -0.12065 -0.305054)
			(end -0.12065 -0.2794)
			(stroke
				(width 0.1)
				(type default)
			)
			(layer "F.Fab")
		)
		(fp_line
			(start -0.12065 -0.2794)
			(end 0.12065 -0.2794)
			(stroke
				(width 0.1)
				(type default)
			)
			(layer "F.Fab")
		)
		(fp_line
			(start -0.12065 0.2794)
			(end -0.12065 0.3048)
			(stroke
				(width 0.1)
				(type default)
			)
			(layer "F.Fab")
		)
		(fp_line
			(start -0.12065 0.3048)
			(end -0.67945 0.3048)
			(stroke
				(width 0.1)
				(type default)
			)
			(layer "F.Fab")
		)
		(fp_line
			(start 0.120396 0.2794)
			(end -0.12065 0.2794)
			(stroke
				(width 0.1)
				(type default)
			)
			(layer "F.Fab")
		)
		(fp_line
			(start 0.120396 0.3048)
			(end 0.120396 0.2794)
			(stroke
				(width 0.1)
				(type default)
			)
			(layer "F.Fab")
		)
		(fp_line
			(start 0.12065 -0.3048)
			(end 0.67945 -0.3048)
			(stroke
				(width 0.1)
				(type default)
			)
			(layer "F.Fab")
		)
		(fp_line
			(start 0.12065 -0.2794)
			(end 0.12065 -0.3048)
			(stroke
				(width 0.1)
				(type default)
			)
			(layer "F.Fab")
		)
		(fp_line
			(start 0.67945 -0.3048)
			(end 0.67945 0.3048)
			(stroke
				(width 0.1)
				(type default)
			)
			(layer "F.Fab")
		)
		(fp_line
			(start 0.67945 0.3048)
			(end 0.120396 0.3048)
			(stroke
				(width 0.1)
				(type default)
			)
			(layer "F.Fab")
		)
		(pad "1" smd circle
			(at -0.40005 0)
			(size 0 0)
			(layers "F.Cu" "F.Mask" "F.Paste")
			(net "PWRGD_CHAF_CPU1_R1")
		)
		(pad "2" smd circle
			(at 0.40005 0)
			(size 0 0)
			(layers "F.Cu" "F.Mask" "F.Paste")
			(net "PWRGD_CHAF_CPU1_R2")
		)
	)
	(footprint ""
		(layer "F.Cu")
		(at 212.993732 -115.716812 180)
		(property "Reference" "R135"
			(at 0 0 180)
			(layer "F.SilkS")
			(hide yes)
			(effects
				(font
					(size 1.27 1.27)
				)
			)
		)
		(property "Value" ""
			(at 0 0 180)
			(layer "F.Fab")
			(effects
				(font
					(size 1.27 1.27)
				)
			)
		)
		(duplicate_pad_numbers_are_jumpers no)
		(fp_line
			(start 0.7874 0.4064)
			(end -0.7874 0.4064)
			(stroke
				(width 0.1524)
				(type default)
			)
			(layer "F.SilkS")
		)
		(fp_line
			(start 0.7874 -0.4064)
			(end 0.7874 0.4064)
			(stroke
				(width 0.1524)
				(type default)
			)
			(layer "F.SilkS")
		)
		(fp_line
			(start -0.7874 0.4064)
			(end -0.7874 -0.4064)
			(stroke
				(width 0.1524)
				(type default)
			)
			(layer "F.SilkS")
		)
		(fp_line
			(start -0.7874 -0.4064)
			(end 0.7874 -0.4064)
			(stroke
				(width 0.1524)
				(type default)
			)
			(layer "F.SilkS")
		)
		(fp_line
			(start 0.67945 0.3048)
			(end 0.120396 0.3048)
			(stroke
				(width 0.1)
				(type default)
			)
			(layer "F.Fab")
		)
		(fp_line
			(start 0.67945 -0.3048)
			(end 0.67945 0.3048)
			(stroke
				(width 0.1)
				(type default)
			)
			(layer "F.Fab")
		)
		(fp_line
			(start 0.12065 -0.2794)
			(end 0.12065 -0.3048)
			(stroke
				(width 0.1)
				(type default)
			)
			(layer "F.Fab")
		)
		(fp_line
			(start 0.12065 -0.3048)
			(end 0.67945 -0.3048)
			(stroke
				(width 0.1)
				(type default)
			)
			(layer "F.Fab")
		)
		(fp_line
			(start 0.120396 0.3048)
			(end 0.120396 0.2794)
			(stroke
				(width 0.1)
				(type default)
			)
			(layer "F.Fab")
		)
		(fp_line
			(start 0.120396 0.2794)
			(end -0.12065 0.2794)
			(stroke
				(width 0.1)
				(type default)
			)
			(layer "F.Fab")
		)
		(fp_line
			(start -0.12065 0.3048)
			(end -0.67945 0.3048)
			(stroke
				(width 0.1)
				(type default)
			)
			(layer "F.Fab")
		)
		(fp_line
			(start -0.12065 0.2794)
			(end -0.12065 0.3048)
			(stroke
				(width 0.1)
				(type default)
			)
			(layer "F.Fab")
		)
		(fp_line
			(start -0.12065 -0.2794)
			(end 0.12065 -0.2794)
			(stroke
				(width 0.1)
				(type default)
			)
			(layer "F.Fab")
		)
		(fp_line
			(start -0.12065 -0.305054)
			(end -0.12065 -0.2794)
			(stroke
				(width 0.1)
				(type default)
			)
			(layer "F.Fab")
		)
		(fp_line
			(start -0.67945 0.3048)
			(end -0.67945 -0.305054)
			(stroke
				(width 0.1)
				(type default)
			)
			(layer "F.Fab")
		)
		(fp_line
			(start -0.67945 -0.305054)
			(end -0.12065 -0.305054)
			(stroke
				(width 0.1)
				(type default)
			)
			(layer "F.Fab")
		)
		(pad "1" smd circle
			(at -0.40005 0 180)
			(size 0 0)
			(layers "F.Cu" "F.Mask" "F.Paste")
			(net "FM_APML_MUX2_SEL")
		)
		(pad "2" smd circle
			(at 0.40005 0 180)
			(size 0 0)
			(layers "F.Cu" "F.Mask" "F.Paste")
			(net "P3V3_AUX")
		)
	)
)
